# T6G (Grand Teton) — schematic netlist excerpt (pin names and nets, part order shuffled) for the footprints in the layout excerpt that follows; sources: Cadence DE-HDL packaged netlist, KiCad conversion of 04192023_DAF0TMB3IC0_F0TG_MB_C_brd_V02_OCP.brd

R1053  Q_RES  0 5% CHIP  pkg 0603LF  page 301 : A = P0V9_CPU0_RT2_2A_2D ; B = P0V9_CPU0_RT2_2A
C784  Q_CAP  0.1UF 10V 10% X7S  pkg C0201  page 301 : A = P0V9_CPU0_RT2_2A ; B = GND
C6115  Q_CAP  1PF 50V 0.05P COG  pkg C0402  page 179 : A = P1V2_CPU0_USB2_DVDD12 ; B = GND

(kicad_pcb
	(version 20260206)
	(generator "pcbnew")
	(generator_version "10.0")
	(general
		(thickness 1.6)
		(legacy_teardrops no)
	)
	(paper "A4")
	(title_block
		(title "04192023_DAF0TMB3IC0_F0TG_MB_C_brd_V02_OCP.brd")
		(comment 1 "Grand Teton / footprints 6332-6334 of 8354")
	)
	(layers
		(0 "F.Cu" signal "TOP")
		(4 "In1.Cu" signal "GND")
		(6 "In2.Cu" signal "IN1")
		(8 "In3.Cu" signal "GND1")
		(10 "In4.Cu" signal "IN2")
		(12 "In5.Cu" signal "GND2")
		(14 "In6.Cu" signal "IN3")
		(16 "In7.Cu" signal "GND3")
		(18 "In8.Cu" signal "VCC")
		(20 "In9.Cu" signal "VCC1")
		(22 "In10.Cu" signal "GND4")
		(24 "In11.Cu" signal "IN4")
		(26 "In12.Cu" signal "GND5")
		(28 "In13.Cu" signal "IN5")
		(30 "In14.Cu" signal "GND6")
		(32 "In15.Cu" signal "IN6")
		(34 "In16.Cu" signal "GND7")
		(2 "B.Cu" signal "BOTTOM")
		(9 "F.Adhes" user "F.Adhesive")
		(11 "B.Adhes" user "B.Adhesive")
		(13 "F.Paste" user "Package Geometry/Pastemask Top")
		(15 "B.Paste" user "Package Geometry/Pastemask Bottom")
		(5 "F.SilkS" user "Ref Des/Silkscreen Top")
		(7 "B.SilkS" user "Ref Des/Silkscreen Bottom")
		(1 "F.Mask" user "Board Geometry/Soldermask Top")
		(3 "B.Mask" user "Board Geometry/Soldermask Bottom")
		(17 "Dwgs.User" user "User.Drawings")
		(19 "Cmts.User" user "User.Comments")
		(21 "Eco1.User" user "User.Eco1")
		(23 "Eco2.User" user "User.Eco2")
		(25 "Edge.Cuts" user "Board Geometry/Outline")
		(27 "Margin" user)
		(31 "F.CrtYd" user "Package Geometry/Place Bound Top")
		(29 "B.CrtYd" user "Package Geometry/Place Bound Bottom")
		(35 "F.Fab" user "Ref Des/Assembly Top")
		(33 "B.Fab" user "Ref Des/Assembly Bottom")
	)
	(footprint ""
		(layer "B.Cu")
		(at 396.989554 -401.624546 180)
		(property "Reference" "R1053"
			(at 0 0 0)
			(layer "B.SilkS")
			(hide yes)
			(effects
				(font
					(size 1.27 1.27)
				)
				(justify mirror)
			)
		)
		(property "Value" ""
			(at 0 0 0)
			(layer "B.Fab")
			(effects
				(font
					(size 1.27 1.27)
				)
				(justify mirror)
			)
		)
		(duplicate_pad_numbers_are_jumpers no)
		(fp_line
			(start 1.2954 0.5842)
			(end 1.2954 -0.5842)
			(stroke
				(width 0.1524)
				(type default)
			)
			(layer "B.SilkS")
		)
		(fp_line
			(start 1.2954 -0.5842)
			(end -1.2954 -0.5842)
			(stroke
				(width 0.1524)
				(type default)
			)
			(layer "B.SilkS")
		)
		(fp_line
			(start -1.2954 0.5842)
			(end 1.2954 0.5842)
			(stroke
				(width 0.1524)
				(type default)
			)
			(layer "B.SilkS")
		)
		(fp_line
			(start -1.2954 -0.5842)
			(end -1.2954 0.5842)
			(stroke
				(width 0.1524)
				(type default)
			)
			(layer "B.SilkS")
		)
		(fp_line
			(start 1.1938 0.4064)
			(end 1.1938 -0.406654)
			(stroke
				(width 0.1)
				(type default)
			)
			(layer "B.Fab")
		)
		(fp_line
			(start 1.1938 -0.406654)
			(end 0.8636 -0.406654)
			(stroke
				(width 0.1)
				(type default)
			)
			(layer "B.Fab")
		)
		(fp_line
			(start 0.8636 0.4572)
			(end 0.8636 0.4318)
			(stroke
				(width 0.1)
				(type default)
			)
			(layer "B.Fab")
		)
		(fp_line
			(start 0.8636 0.4318)
			(end 0.8636 0.4064)
			(stroke
				(width 0.1)
				(type default)
			)
			(layer "B.Fab")
		)
		(fp_line
			(start 0.8636 0.4064)
			(end 1.1938 0.4064)
			(stroke
				(width 0.1)
				(type default)
			)
			(layer "B.Fab")
		)
		(fp_line
			(start 0.8636 -0.406654)
			(end 0.8636 -0.4572)
			(stroke
				(width 0.1)
				(type default)
			)
			(layer "B.Fab")
		)
		(fp_line
			(start 0.8636 -0.4572)
			(end -0.8636 -0.4572)
			(stroke
				(width 0.1)
				(type default)
			)
			(layer "B.Fab")
		)
		(fp_line
			(start -0.8636 0.4572)
			(end 0.8636 0.4572)
			(stroke
				(width 0.1)
				(type default)
			)
			(layer "B.Fab")
		)
		(fp_line
			(start -0.8636 0.4064)
			(end -0.8636 0.4572)
			(stroke
				(width 0.1)
				(type default)
			)
			(layer "B.Fab")
		)
		(fp_line
			(start -0.8636 -0.406654)
			(end -1.1938 -0.406654)
			(stroke
				(width 0.1)
				(type default)
			)
			(layer "B.Fab")
		)
		(fp_line
			(start -0.8636 -0.4572)
			(end -0.8636 -0.406654)
			(stroke
				(width 0.1)
				(type default)
			)
			(layer "B.Fab")
		)
		(fp_line
			(start -1.1938 0.4064)
			(end -0.8636 0.4064)
			(stroke
				(width 0.1)
				(type default)
			)
			(layer "B.Fab")
		)
		(fp_line
			(start -1.1938 -0.406654)
			(end -1.1938 0.4064)
			(stroke
				(width 0.1)
				(type default)
			)
			(layer "B.Fab")
		)
		(pad "1" smd rect
			(at 0.7366 0 90)
			(size 0.7112 0.8128)
			(layers "B.Cu" "B.Mask" "B.Paste")
			(net "P0V9_CPU0_RT2_2A_2D")
		)
		(pad "2" smd rect
			(at -0.7366 0 90)
			(size 0.7112 0.8128)
			(layers "B.Cu" "B.Mask" "B.Paste")
			(net "P0V9_CPU0_RT2_2A")
		)
	)
	(footprint ""
		(layer "B.Cu")
		(at 110.48746 -35.088068 90)
		(property "Reference" "C6115"
			(at 0 0 90)
			(layer "B.SilkS")
			(hide yes)
			(effects
				(font
					(size 1.27 1.27)
				)
				(justify mirror)
			)
		)
		(property "Value" ""
			(at 0 0 90)
			(layer "B.Fab")
			(effects
				(font
					(size 1.27 1.27)
				)
				(justify mirror)
			)
		)
		(duplicate_pad_numbers_are_jumpers no)
		(fp_line
			(start 0.7874 -0.4064)
			(end -0.7874 -0.4064)
			(stroke
				(width 0.1524)
				(type default)
			)
			(layer "B.SilkS")
		)
		(fp_line
			(start -0.7874 -0.4064)
			(end -0.7874 0.4064)
			(stroke
				(width 0.1524)
				(type default)
			)
			(layer "B.SilkS")
		)
		(fp_line
			(start 0.7874 0.4064)
			(end 0.7874 -0.4064)
			(stroke
				(width 0.1524)
				(type default)
			)
			(layer "B.SilkS")
		)
		(fp_line
			(start -0.7874 0.4064)
			(end 0.7874 0.4064)
			(stroke
				(width 0.1524)
				(type default)
			)
			(layer "B.SilkS")
		)
		(fp_line
			(start 0.67945 -0.305054)
			(end 0.12065 -0.305054)
			(stroke
				(width 0.1)
				(type default)
			)
			(layer "B.Fab")
		)
		(fp_line
			(start 0.12065 -0.305054)
			(end 0.12065 -0.2794)
			(stroke
				(width 0.1)
				(type default)
			)
			(layer "B.Fab")
		)
		(fp_line
			(start -0.12065 -0.3048)
			(end -0.67945 -0.3048)
			(stroke
				(width 0.1)
				(type default)
			)
			(layer "B.Fab")
		)
		(fp_line
			(start -0.67945 -0.3048)
			(end -0.67945 0.3048)
			(stroke
				(width 0.1)
				(type default)
			)
			(layer "B.Fab")
		)
		(fp_line
			(start 0.12065 -0.2794)
			(end -0.12065 -0.2794)
			(stroke
				(width 0.1)
				(type default)
			)
			(layer "B.Fab")
		)
		(fp_line
			(start -0.12065 -0.2794)
			(end -0.12065 -0.3048)
			(stroke
				(width 0.1)
				(type default)
			)
			(layer "B.Fab")
		)
		(fp_line
			(start 0.12065 0.2794)
			(end 0.12065 0.3048)
			(stroke
				(width 0.1)
				(type default)
			)
			(layer "B.Fab")
		)
		(fp_line
			(start -0.120396 0.2794)
			(end 0.12065 0.2794)
			(stroke
				(width 0.1)
				(type default)
			)
			(layer "B.Fab")
		)
		(fp_line
			(start 0.67945 0.3048)
			(end 0.67945 -0.305054)
			(stroke
				(width 0.1)
				(type default)
			)
			(layer "B.Fab")
		)
		(fp_line
			(start 0.12065 0.3048)
			(end 0.67945 0.3048)
			(stroke
				(width 0.1)
				(type default)
			)
			(layer "B.Fab")
		)
		(fp_line
			(start -0.120396 0.3048)
			(end -0.120396 0.2794)
			(stroke
				(width 0.1)
				(type default)
			)
			(layer "B.Fab")
		)
		(fp_line
			(start -0.67945 0.3048)
			(end -0.120396 0.3048)
			(stroke
				(width 0.1)
				(type default)
			)
			(layer "B.Fab")
		)
		(pad "1" smd circle
			(at 0.40005 0 270)
			(size 0 0)
			(layers "B.Cu" "B.Mask" "B.Paste")
			(net "P1V2_CPU0_USB2_DVDD12")
		)
		(pad "2" smd circle
			(at -0.40005 0 270)
			(size 0 0)
			(layers "B.Cu" "B.Mask" "B.Paste")
			(net "GND")
		)
	)
	(footprint ""
		(layer "B.Cu")
		(at 400.727672 -396.991078 90)
		(property "Reference" "C784"
			(at 0 0 90)
			(layer "B.SilkS")
			(hide yes)
			(effects
				(font
					(size 1.27 1.27)
				)
				(justify mirror)
			)
		)
		(property "Value" ""
			(at 0 0 90)
			(layer "B.Fab")
			(effects
				(font
					(size 1.27 1.27)
				)
				(justify mirror)
			)
		)
		(duplicate_pad_numbers_are_jumpers no)
		(fp_line
			(start 0.299974 -0.150114)
			(end -0.299974 -0.150114)
			(stroke
				(width 0.1)
				(type default)
			)
			(layer "B.Fab")
		)
		(fp_line
			(start -0.299974 -0.150114)
			(end -0.299974 0.150114)
			(stroke
				(width 0.1)
				(type default)
			)
			(layer "B.Fab")
		)
		(fp_line
			(start 0.299974 0.150114)
			(end 0.299974 -0.150114)
			(stroke
				(width 0.1)
				(type default)
			)
			(layer "B.Fab")
		)
		(fp_line
			(start -0.299974 0.150114)
			(end 0.299974 0.150114)
			(stroke
				(width 0.1)
				(type default)
			)
			(layer "B.Fab")
		)
		(pad "1" smd rect
			(at 0.2667 0 270)
			(size 0.3048 0.381)
			(layers "B.Cu" "B.Mask" "B.Paste")
			(net "P0V9_CPU0_RT2_2A")
		)
		(pad "2" smd rect
			(at -0.2667 0 270)
			(size 0.3048 0.381)
			(layers "B.Cu" "B.Mask" "B.Paste")
			(net "GND")
		)
	)
)
